# T6G (Grand Teton) — schematic netlist excerpt (pin names and nets, part order shuffled) for the footprints in the layout excerpt that follows; sources: Cadence DE-HDL packaged netlist, KiCad conversion of 04192023_DAF0TMB3IC0_F0TG_MB_C_brd_V02_OCP.brd

PU6501  MPQ8633BGLEC838Z  MPQ8633BGLE-C838-Z IC  pkg QFN14_4X3  page 361
  BST  = SW_P1V8_RETIMER_CPU1_BST
  AGND  = GND
  CS  = P1V8_RETIMER_CPU1_CS
  MODE  = P1V8_RETIMER_CPU1_MODE
  TRK_REF  = P1V8_RETIMER_CPU1_REF
  RGND  = GND
  FB  = P1V8_RETIMER_CPU1_FB
  EN  = P1V8_RETIMER_CPU1_EN
  PGOOD  = PWRGD_P1V8_RETIMER_CPU1
  VIN1  = SW_P12V_AUX_P1V8_RETIMER_CPU1_FLT
  PGND  = GND
  VCC  = P1V8_RETIMER_CPU1_VCC
  SW  = SW_P1V8_RETIMER_CPU1_SW
  VIN2  = SW_P12V_AUX_P1V8_RETIMER_CPU1_FLT

PC150_1  Q_CAP  1UF 25V 10% X6S  pkg C0402  page 205 : A = SW_P12V_AUX_PVDDIO_P0_FLT ; B = GND

(kicad_pcb
	(version 20260206)
	(generator "pcbnew")
	(generator_version "10.0")
	(general
		(thickness 1.6)
		(legacy_teardrops no)
	)
	(paper "A4")
	(title_block
		(title "04192023_DAF0TMB3IC0_F0TG_MB_C_brd_V02_OCP.brd")
		(comment 1 "Grand Teton / footprints 4054-4055 of 8354")
	)
	(layers
		(0 "F.Cu" signal "TOP")
		(4 "In1.Cu" signal "GND")
		(6 "In2.Cu" signal "IN1")
		(8 "In3.Cu" signal "GND1")
		(10 "In4.Cu" signal "IN2")
		(12 "In5.Cu" signal "GND2")
		(14 "In6.Cu" signal "IN3")
		(16 "In7.Cu" signal "GND3")
		(18 "In8.Cu" signal "VCC")
		(20 "In9.Cu" signal "VCC1")
		(22 "In10.Cu" signal "GND4")
		(24 "In11.Cu" signal "IN4")
		(26 "In12.Cu" signal "GND5")
		(28 "In13.Cu" signal "IN5")
		(30 "In14.Cu" signal "GND6")
		(32 "In15.Cu" signal "IN6")
		(34 "In16.Cu" signal "GND7")
		(2 "B.Cu" signal "BOTTOM")
		(9 "F.Adhes" user "F.Adhesive")
		(11 "B.Adhes" user "B.Adhesive")
		(13 "F.Paste" user "Package Geometry/Pastemask Top")
		(15 "B.Paste" user "Package Geometry/Pastemask Bottom")
		(5 "F.SilkS" user "Ref Des/Silkscreen Top")
		(7 "B.SilkS" user "Ref Des/Silkscreen Bottom")
		(1 "F.Mask" user "Board Geometry/Soldermask Top")
		(3 "B.Mask" user "Board Geometry/Soldermask Bottom")
		(17 "Dwgs.User" user "User.Drawings")
		(19 "Cmts.User" user "User.Comments")
		(21 "Eco1.User" user "User.Eco1")
		(23 "Eco2.User" user "User.Eco2")
		(25 "Edge.Cuts" user "Board Geometry/Outline")
		(27 "Margin" user)
		(31 "F.CrtYd" user "Package Geometry/Place Bound Top")
		(29 "B.CrtYd" user "Package Geometry/Place Bound Bottom")
		(35 "F.Fab" user "Ref Des/Assembly Top")
		(33 "B.Fab" user "Ref Des/Assembly Bottom")
	)
	(footprint ""
		(layer "F.Cu")
		(at 231.42702 -291.761926)
		(property "Reference" "PU6501"
			(at 1.014476 -3.50774 0)
			(unlocked yes)
			(layer "F.SilkS")
			(effects
				(font
					(size 0.7874 0.5842)
					(thickness 0.1524)
				)
				(justify left)
			)
		)
		(property "Value" ""
			(at 0 0 0)
			(layer "F.Fab")
			(effects
				(font
					(size 1.27 1.27)
				)
			)
		)
		(duplicate_pad_numbers_are_jumpers no)
		(fp_line
			(start -1.549908 -2.050034)
			(end -1.549908 -1.9812)
			(stroke
				(width 0.1524)
				(type default)
			)
			(layer "F.SilkS")
		)
		(fp_line
			(start -1.549908 1.9812)
			(end -1.549908 2.050034)
			(stroke
				(width 0.1524)
				(type default)
			)
			(layer "F.SilkS")
		)
		(fp_line
			(start -1.549908 2.050034)
			(end -0.5842 2.050034)
			(stroke
				(width 0.1524)
				(type default)
			)
			(layer "F.SilkS")
		)
		(fp_line
			(start -0.5842 -2.050034)
			(end -1.549908 -2.050034)
			(stroke
				(width 0.1524)
				(type default)
			)
			(layer "F.SilkS")
		)
		(fp_line
			(start 0 2.050034)
			(end 1.549908 2.050034)
			(stroke
				(width 0.1524)
				(type default)
			)
			(layer "F.SilkS")
		)
		(fp_line
			(start 1.549908 -2.050034)
			(end 0.5842 -2.050034)
			(stroke
				(width 0.1524)
				(type default)
			)
			(layer "F.SilkS")
		)
		(fp_line
			(start 1.549908 -1.9812)
			(end 1.549908 -2.050034)
			(stroke
				(width 0.1524)
				(type default)
			)
			(layer "F.SilkS")
		)
		(fp_line
			(start 1.549908 2.050034)
			(end 1.549908 1.9304)
			(stroke
				(width 0.1524)
				(type default)
			)
			(layer "F.SilkS")
		)
		(fp_poly
			(pts
				(xy -2.9464 -2.208022) (xy -2.9464 -1.192022) (xy -1.9304 -1.700022)
			)
			(stroke
				(width 0)
				(type default)
			)
			(fill yes)
			(layer "F.SilkS")
		)
		(fp_line
			(start -1.549908 -2.050034)
			(end -1.549908 2.050034)
			(stroke
				(width 0.1)
				(type default)
			)
			(layer "F.Fab")
		)
		(fp_line
			(start -1.549908 2.050034)
			(end 1.549908 2.050034)
			(stroke
				(width 0.1)
				(type default)
			)
			(layer "F.Fab")
		)
		(fp_line
			(start 1.549908 -2.050034)
			(end -1.549908 -2.050034)
			(stroke
				(width 0.1)
				(type default)
			)
			(layer "F.Fab")
		)
		(fp_line
			(start 1.549908 2.050034)
			(end 1.549908 -2.050034)
			(stroke
				(width 0.1)
				(type default)
			)
			(layer "F.Fab")
		)
		(fp_poly
			(pts
				(xy -2.9464 -2.208022) (xy -2.9464 -1.192022) (xy -1.9304 -1.700022)
			)
			(stroke
				(width 0)
				(type default)
			)
			(fill yes)
			(layer "F.Fab")
		)
		(pad "1" smd circle
			(at -1.35001 -1.700022)
			(size 0 0)
			(layers "F.Cu" "F.Mask" "F.Paste")
			(net "SW_P1V8_RETIMER_CPU1_BST")
		)
		(pad "2" smd rect
			(at -1.400048 -1.199896 90)
			(size 0.1778 0.8128)
			(layers "F.Cu" "F.Mask" "F.Paste")
			(net "GND")
		)
		(pad "3" smd rect
			(at -1.400048 -0.8001 90)
			(size 0.1778 0.8128)
			(layers "F.Cu" "F.Mask" "F.Paste")
			(net "P1V8_RETIMER_CPU1_CS")
		)
		(pad "4" smd rect
			(at -1.400048 -0.40005 90)
			(size 0.1778 0.8128)
			(layers "F.Cu" "F.Mask" "F.Paste")
			(net "P1V8_RETIMER_CPU1_MODE")
		)
		(pad "5" smd rect
			(at -1.400048 0 90)
			(size 0.1778 0.8128)
			(layers "F.Cu" "F.Mask" "F.Paste")
			(net "P1V8_RETIMER_CPU1_REF")
		)
		(pad "6" smd rect
			(at -1.400048 0.40005 90)
			(size 0.1778 0.8128)
			(layers "F.Cu" "F.Mask" "F.Paste")
			(net "GND")
		)
		(pad "7" smd rect
			(at -1.400048 0.8001 90)
			(size 0.1778 0.8128)
			(layers "F.Cu" "F.Mask" "F.Paste")
			(net "P1V8_RETIMER_CPU1_FB")
		)
		(pad "8" smd rect
			(at -1.400048 1.199896 90)
			(size 0.1778 0.8128)
			(layers "F.Cu" "F.Mask" "F.Paste")
			(net "P1V8_RETIMER_CPU1_EN")
		)
		(pad "9" smd rect
			(at -1.400048 1.700022 90)
			(size 0.3048 0.8128)
			(layers "F.Cu" "F.Mask" "F.Paste")
			(net "PWRGD_P1V8_RETIMER_CPU1")
		)
		(pad "10" smd rect
			(at -0.299974 1.299972)
			(size 0.3048 2.0066)
			(layers "F.Cu" "F.Mask" "F.Paste")
			(net "SW_P12V_AUX_P1V8_RETIMER_CPU1_FLT")
		)
		(pad "11_18" smd circle
			(at 1.175004 0.275082)
			(size 0 0)
			(layers "F.Cu" "F.Mask" "F.Paste")
			(net "GND")
		)
		(pad "19" smd rect
			(at 1.400048 -1.700022 270)
			(size 0.3048 0.8128)
			(layers "F.Cu" "F.Mask" "F.Paste")
			(net "P1V8_RETIMER_CPU1_VCC")
		)
		(pad "20" smd rect
			(at 0.299974 -1.299972)
			(size 0.3048 2.0066)
			(layers "F.Cu" "F.Mask" "F.Paste")
			(net "SW_P1V8_RETIMER_CPU1_SW")
		)
		(pad "21" smd rect
			(at -0.299974 -1.299972)
			(size 0.3048 2.0066)
			(layers "F.Cu" "F.Mask" "F.Paste")
			(net "SW_P12V_AUX_P1V8_RETIMER_CPU1_FLT")
		)
	)
	(footprint ""
		(layer "F.Cu")
		(at 303.999392 -346.866464 -90)
		(property "Reference" "PC150_1"
			(at 0 0 270)
			(layer "F.SilkS")
			(hide yes)
			(effects
				(font
					(size 1.27 1.27)
				)
			)
		)
		(property "Value" ""
			(at 0 0 270)
			(layer "F.Fab")
			(effects
				(font
					(size 1.27 1.27)
				)
			)
		)
		(duplicate_pad_numbers_are_jumpers no)
		(fp_line
			(start -0.7874 0.4064)
			(end -0.7874 -0.4064)
			(stroke
				(width 0.1524)
				(type default)
			)
			(layer "F.SilkS")
		)
		(fp_line
			(start 0.7874 0.4064)
			(end -0.7874 0.4064)
			(stroke
				(width 0.1524)
				(type default)
			)
			(layer "F.SilkS")
		)
		(fp_line
			(start -0.7874 -0.4064)
			(end 0.7874 -0.4064)
			(stroke
				(width 0.1524)
				(type default)
			)
			(layer "F.SilkS")
		)
		(fp_line
			(start 0.7874 -0.4064)
			(end 0.7874 0.4064)
			(stroke
				(width 0.1524)
				(type default)
			)
			(layer "F.SilkS")
		)
		(fp_line
			(start -0.67945 0.3048)
			(end -0.67945 -0.305054)
			(stroke
				(width 0.1)
				(type default)
			)
			(layer "F.Fab")
		)
		(fp_line
			(start -0.12065 0.3048)
			(end -0.67945 0.3048)
			(stroke
				(width 0.1)
				(type default)
			)
			(layer "F.Fab")
		)
		(fp_line
			(start 0.120396 0.3048)
			(end 0.120396 0.2794)
			(stroke
				(width 0.1)
				(type default)
			)
			(layer "F.Fab")
		)
		(fp_line
			(start 0.67945 0.3048)
			(end 0.120396 0.3048)
			(stroke
				(width 0.1)
				(type default)
			)
			(layer "F.Fab")
		)
		(fp_line
			(start -0.12065 0.2794)
			(end -0.12065 0.3048)
			(stroke
				(width 0.1)
				(type default)
			)
			(layer "F.Fab")
		)
		(fp_line
			(start 0.120396 0.2794)
			(end -0.12065 0.2794)
			(stroke
				(width 0.1)
				(type default)
			)
			(layer "F.Fab")
		)
		(fp_line
			(start -0.12065 -0.2794)
			(end 0.12065 -0.2794)
			(stroke
				(width 0.1)
				(type default)
			)
			(layer "F.Fab")
		)
		(fp_line
			(start 0.12065 -0.2794)
			(end 0.12065 -0.3048)
			(stroke
				(width 0.1)
				(type default)
			)
			(layer "F.Fab")
		)
		(fp_line
			(start 0.12065 -0.3048)
			(end 0.67945 -0.3048)
			(stroke
				(width 0.1)
				(type default)
			)
			(layer "F.Fab")
		)
		(fp_line
			(start 0.67945 -0.3048)
			(end 0.67945 0.3048)
			(stroke
				(width 0.1)
				(type default)
			)
			(layer "F.Fab")
		)
		(fp_line
			(start -0.67945 -0.305054)
			(end -0.12065 -0.305054)
			(stroke
				(width 0.1)
				(type default)
			)
			(layer "F.Fab")
		)
		(fp_line
			(start -0.12065 -0.305054)
			(end -0.12065 -0.2794)
			(stroke
				(width 0.1)
				(type default)
			)
			(layer "F.Fab")
		)
		(pad "1" smd circle
			(at -0.40005 0 270)
			(size 0 0)
			(layers "F.Cu" "F.Mask" "F.Paste")
			(net "SW_P12V_AUX_PVDDIO_P0_FLT")
		)
		(pad "2" smd circle
			(at 0.40005 0 270)
			(size 0 0)
			(layers "F.Cu" "F.Mask" "F.Paste")
			(net "GND")
		)
	)
)
